(kicad_pcb
	(version 20241229)
	(generator "pcbnew")
	(generator_version "9.0")
	(general
		(thickness 1.711)
		(legacy_teardrops no)
	)
	(paper "A4")
	(title_block
		(title "Antmicro Baseboard for Jetson AGX Thor")
		(date "2026-02-18")
		(rev "1.1.0")
		(company "Antmicro Ltd")
		(comment 1 "www.antmicro.com")
		(comment 9 "footprints 283-287 of 1170")
	)
	(layers
		(0 "F.Cu" signal)
		(4 "In1.Cu" signal)
		(6 "In2.Cu" signal)
		(8 "In3.Cu" signal)
		(10 "In4.Cu" jumper)
		(12 "In5.Cu" signal)
		(14 "In6.Cu" signal)
		(16 "In7.Cu" signal)
		(18 "In8.Cu" signal)
		(2 "B.Cu" signal)
		(9 "F.Adhes" user "F.Adhesive")
		(11 "B.Adhes" user "B.Adhesive")
		(13 "F.Paste" user)
		(15 "B.Paste" user)
		(5 "F.SilkS" user "F.Silkscreen")
		(7 "B.SilkS" user "B.Silkscreen")
		(1 "F.Mask" user)
		(3 "B.Mask" user)
		(17 "Dwgs.User" user "User.Drawings")
		(19 "Cmts.User" user "User.Comments")
		(21 "Eco1.User" user "User.Eco1")
		(23 "Eco2.User" user "User.Eco2")
		(25 "Edge.Cuts" user)
		(27 "Margin" user)
		(31 "F.CrtYd" user "F.Courtyard")
		(29 "B.CrtYd" user "B.Courtyard")
		(35 "F.Fab" user)
		(33 "B.Fab" user)
	)
	(footprint "antmicro-footprints:C_0805_2012Metric"
		(layer "F.Cu")
		(at 171.38 79.81 90)
		(descr "Capacitor SMD 0805")
		(tags "capacitor SMD 0805")
		(property "Reference" "C292"
			(at -4.67 0.23 90)
			(layer "F.SilkS")
			(effects
				(font
					(size 0.7 0.7)
					(thickness 0.15)
				)
				(justify left bottom)
			)
		)
		(property "Value" "C_22u_25V_0805"
			(at -2.055717 1.963152 90)
			(layer "F.Fab")
			(effects
				(font
					(size 0.7 0.7)
					(thickness 0.15)
				)
				(justify left bottom)
			)
		)
		(property "Datasheet" "https://product.samsungsem.com/mlcc/CL21A226MAYNNN.do"
			(at 0 0 90)
			(layer "F.Fab")
			(hide yes)
			(effects
				(font
					(size 1.27 1.27)
					(thickness 0.15)
				)
			)
		)
		(property "Description" "SMT Multilayer Ceramic Capacitor, 22uF, +/-20%, 25V, X5R, 0805 [2012 Metric]"
			(at 0 0 90)
			(layer "F.Fab")
			(hide yes)
			(effects
				(font
					(size 1.27 1.27)
					(thickness 0.15)
				)
			)
		)
		(property "MPN" "CL21A226MAYNNNE"
			(at 0 0 90)
			(unlocked yes)
			(layer "F.Fab")
			(hide yes)
			(effects
				(font
					(size 1 1)
					(thickness 0.15)
				)
			)
		)
		(property "Manufacturer" "Samsung Electro-Mechanics"
			(at 0 0 90)
			(unlocked yes)
			(layer "F.Fab")
			(hide yes)
			(effects
				(font
					(size 1 1)
					(thickness 0.15)
				)
			)
		)
		(property "License" "Apache-2.0"
			(at 0 0 90)
			(unlocked yes)
			(layer "F.Fab")
			(hide yes)
			(effects
				(font
					(size 1 1)
					(thickness 0.15)
				)
			)
		)
		(property "Author" "Antmicro"
			(at 0 0 90)
			(unlocked yes)
			(layer "F.Fab")
			(hide yes)
			(effects
				(font
					(size 1 1)
					(thickness 0.15)
				)
			)
		)
		(property "Val" "22u"
			(at 0 0 90)
			(unlocked yes)
			(layer "F.Fab")
			(hide yes)
			(effects
				(font
					(size 1 1)
					(thickness 0.15)
				)
			)
		)
		(property "Voltage" "25V"
			(at 0 0 90)
			(unlocked yes)
			(layer "F.Fab")
			(hide yes)
			(effects
				(font
					(size 1 1)
					(thickness 0.15)
				)
			)
		)
		(property "Dielectric" "X5R"
			(at 0 0 90)
			(unlocked yes)
			(layer "F.Fab")
			(hide yes)
			(effects
				(font
					(size 1 1)
					(thickness 0.15)
				)
			)
		)
		(property "Public" "False"
			(at 0 0 90)
			(unlocked yes)
			(layer "F.Fab")
			(hide yes)
			(effects
				(font
					(size 1 1)
					(thickness 0.15)
				)
			)
		)
		(component_classes
			(class "DCDC_20V")
		)
		(sheetname "/DCDC/")
		(sheetfile "dcdc.kicad_sch")
		(attr smd)
		(fp_line
			(start -0.3 -0.7)
			(end 0.3 -0.7)
			(stroke
				(width 0.15)
				(type solid)
			)
			(layer "F.SilkS")
		)
		(fp_line
			(start -0.3 0.7)
			(end 0.3 0.7)
			(stroke
				(width 0.15)
				(type solid)
			)
			(layer "F.SilkS")
		)
		(fp_rect
			(start 1.95 -0.9)
			(end -1.95 0.9)
			(stroke
				(width 0.05)
				(type default)
			)
			(fill no)
			(layer "F.CrtYd")
		)
		(fp_rect
			(start -0.95 -0.675)
			(end 0.95 0.675)
			(stroke
				(width 0.15)
				(type solid)
			)
			(fill no)
			(layer "F.Fab")
		)
		(fp_text user "Author: Antmicro"
			(at -1.9 5.947 90)
			(layer "F.Fab")
			(effects
				(font
					(size 0.7 0.7)
					(thickness 0.15)
				)
				(justify left bottom)
			)
		)
		(fp_text user "License: Apache-2.0"
			(at -1.9 4.947 90)
			(layer "F.Fab")
			(effects
				(font
					(size 0.7 0.7)
					(thickness 0.15)
				)
				(justify left bottom)
			)
		)
		(fp_text user "${REFERENCE}"
			(at -1.9 3.947 90)
			(layer "F.Fab")
			(effects
				(font
					(size 0.7 0.7)
					(thickness 0.15)
				)
				(justify left bottom)
			)
		)
		(pad "1" smd roundrect
			(at -1.1 0 90)
			(size 1.2 1.3)
			(layers "F.Cu" "F.Mask" "F.Paste")
			(roundrect_rratio 0.25)
			(net 1 "GND")
			(pintype "passive")
		)
		(pad "2" smd roundrect
			(at 1.1 0 90)
			(size 1.2 1.3)
			(layers "F.Cu" "F.Mask" "F.Paste")
			(roundrect_rratio 0.25)
			(net 1105 "/DCDC/20V_OUT")
			(pintype "passive")
		)
	)
	(footprint "antmicro-footprints:C_0805_2012Metric"
		(layer "F.Cu")
		(at 170.86 146.32 -90)
		(descr "Capacitor SMD 0805")
		(tags "capacitor SMD 0805")
		(property "Reference" "C235"
			(at 1.89 -0.56 90)
			(layer "F.SilkS")
			(effects
				(font
					(size 0.7 0.7)
					(thickness 0.15)
				)
				(justify right top)
			)
		)
		(property "Value" "C_22u_25V_0805"
			(at -2.055717 1.963152 90)
			(layer "F.Fab")
			(effects
				(font
					(size 0.7 0.7)
					(thickness 0.15)
				)
				(justify right top)
			)
		)
		(property "Datasheet" "https://product.samsungsem.com/mlcc/CL21A226MAYNNN.do"
			(at 0 0 90)
			(layer "F.Fab")
			(hide yes)
			(effects
				(font
					(size 1.27 1.27)
					(thickness 0.15)
				)
			)
		)
		(property "Description" "SMT Multilayer Ceramic Capacitor, 22uF, +/-20%, 25V, X5R, 0805 [2012 Metric]"
			(at 0 0 90)
			(layer "F.Fab")
			(hide yes)
			(effects
				(font
					(size 1.27 1.27)
					(thickness 0.15)
				)
			)
		)
		(property "Manufacturer" "Samsung Electro-Mechanics"
			(at 0 0 270)
			(unlocked yes)
			(layer "F.Fab")
			(hide yes)
			(effects
				(font
					(size 1 1)
					(thickness 0.15)
				)
			)
		)
		(property "MPN" "CL21A226MAYNNNE"
			(at 0 0 270)
			(unlocked yes)
			(layer "F.Fab")
			(hide yes)
			(effects
				(font
					(size 1 1)
					(thickness 0.15)
				)
			)
		)
		(property "Val" "22u"
			(at 0 0 270)
			(unlocked yes)
			(layer "F.Fab")
			(hide yes)
			(effects
				(font
					(size 1 1)
					(thickness 0.15)
				)
			)
		)
		(property "License" "Apache-2.0"
			(at 0 0 270)
			(unlocked yes)
			(layer "F.Fab")
			(hide yes)
			(effects
				(font
					(size 1 1)
					(thickness 0.15)
				)
			)
		)
		(property "Author" "Antmicro"
			(at 0 0 270)
			(unlocked yes)
			(layer "F.Fab")
			(hide yes)
			(effects
				(font
					(size 1 1)
					(thickness 0.15)
				)
			)
		)
		(property "Voltage" "25V"
			(at 0 0 270)
			(unlocked yes)
			(layer "F.Fab")
			(hide yes)
			(effects
				(font
					(size 1 1)
					(thickness 0.15)
				)
			)
		)
		(property "Dielectric" "X5R"
			(at 0 0 270)
			(unlocked yes)
			(layer "F.Fab")
			(hide yes)
			(effects
				(font
					(size 1 1)
					(thickness 0.15)
				)
			)
		)
		(property "Public" "False"
			(at 0 0 270)
			(unlocked yes)
			(layer "F.Fab")
			(hide yes)
			(effects
				(font
					(size 1 1)
					(thickness 0.15)
				)
			)
		)
		(sheetname "/DCDC/")
		(sheetfile "dcdc.kicad_sch")
		(attr smd)
		(fp_line
			(start -0.3 0.7)
			(end 0.3 0.7)
			(stroke
				(width 0.15)
				(type solid)
			)
			(layer "F.SilkS")
		)
		(fp_line
			(start -0.3 -0.7)
			(end 0.3 -0.7)
			(stroke
				(width 0.15)
				(type solid)
			)
			(layer "F.SilkS")
		)
		(fp_rect
			(start 1.95 -0.9)
			(end -1.95 0.9)
			(stroke
				(width 0.05)
				(type default)
			)
			(fill no)
			(layer "F.CrtYd")
		)
		(fp_rect
			(start -0.95 -0.675)
			(end 0.95 0.675)
			(stroke
				(width 0.15)
				(type solid)
			)
			(fill no)
			(layer "F.Fab")
		)
		(fp_text user "Author: Antmicro"
			(at -1.9 5.947 90)
			(layer "F.Fab")
			(effects
				(font
					(size 0.7 0.7)
					(thickness 0.15)
				)
				(justify right top)
			)
		)
		(fp_text user "${REFERENCE}"
			(at -1.9 3.947 90)
			(layer "F.Fab")
			(effects
				(font
					(size 0.7 0.7)
					(thickness 0.15)
				)
				(justify right top)
			)
		)
		(fp_text user "License: Apache-2.0"
			(at -1.9 4.947 90)
			(layer "F.Fab")
			(effects
				(font
					(size 0.7 0.7)
					(thickness 0.15)
				)
				(justify right top)
			)
		)
		(pad "1" smd roundrect
			(at -1.1 0 270)
			(size 1.2 1.3)
			(layers "F.Cu" "F.Mask" "F.Paste")
			(roundrect_rratio 0.25)
			(net 1 "GND")
			(pintype "passive")
		)
		(pad "2" smd roundrect
			(at 1.1 0 270)
			(size 1.2 1.3)
			(layers "F.Cu" "F.Mask" "F.Paste")
			(roundrect_rratio 0.25)
			(net 880 "/DCDC/12V_OUT")
			(pintype "passive")
		)
	)
	(footprint "antmicro-footprints:R_0402_1005Metric"
		(layer "F.Cu")
		(at 161.99 62.8 90)
		(descr "Resistor SMD 0402")
		(tags "resistor SMD 0402")
		(property "Reference" "R342"
			(at -1.4 1.51 90)
			(layer "F.SilkS")
			(effects
				(font
					(size 0.7 0.7)
					(thickness 0.15)
				)
				(justify left bottom)
			)
		)
		(property "Value" "R_10k_0402"
			(at -1.011843 1.772046 90)
			(layer "F.Fab")
			(effects
				(font
					(size 0.7 0.7)
					(thickness 0.15)
				)
				(justify left bottom)
			)
		)
		(property "Datasheet" "https://www.bourns.com/docs/product-datasheets/cr.pdf"
			(at 0 0 90)
			(layer "F.Fab")
			(hide yes)
			(effects
				(font
					(size 1.27 1.27)
					(thickness 0.15)
				)
			)
		)
		(property "Description" "SMD Chip Resistor, 10 kohm, ± 1%, 62.5 mW, 0402 [1005 Metric], Thick Film, General Purpose"
			(at 0 0 90)
			(layer "F.Fab")
			(hide yes)
			(effects
				(font
					(size 1.27 1.27)
					(thickness 0.15)
				)
			)
		)
		(property "MPN" "CR0402-FX-1002GLF"
			(at 0 0 90)
			(unlocked yes)
			(layer "F.Fab")
			(hide yes)
			(effects
				(font
					(size 1 1)
					(thickness 0.15)
				)
			)
		)
		(property "Manufacturer" "Bourns"
			(at 0 0 90)
			(unlocked yes)
			(layer "F.Fab")
			(hide yes)
			(effects
				(font
					(size 1 1)
					(thickness 0.15)
				)
			)
		)
		(property "License" "Apache-2.0"
			(at 0 0 90)
			(unlocked yes)
			(layer "F.Fab")
			(hide yes)
			(effects
				(font
					(size 1 1)
					(thickness 0.15)
				)
			)
		)
		(property "Author" "Antmicro"
			(at 0 0 90)
			(unlocked yes)
			(layer "F.Fab")
			(hide yes)
			(effects
				(font
					(size 1 1)
					(thickness 0.15)
				)
			)
		)
		(property "Val" "10k"
			(at 0 0 90)
			(unlocked yes)
			(layer "F.Fab")
			(hide yes)
			(effects
				(font
					(size 1 1)
					(thickness 0.15)
				)
			)
		)
		(property "Tolerance" "1%"
			(at 0 0 90)
			(unlocked yes)
			(layer "F.Fab")
			(hide yes)
			(effects
				(font
					(size 1 1)
					(thickness 0.15)
				)
			)
		)
		(sheetname "/SoM_IO2/")
		(sheetfile "som_io2.kicad_sch")
		(attr smd exclude_from_pos_files exclude_from_bom dnp)
		(fp_poly
			(pts
				(xy -0.925 -0.47) (xy 0.925 -0.47) (xy 0.925 0.47) (xy -0.925 0.47)
			)
			(stroke
				(width 0.05)
				(type default)
			)
			(fill no)
			(layer "F.CrtYd")
		)
		(fp_poly
			(pts
				(xy -0.5 -0.25) (xy 0.5 -0.25) (xy 0.5 0.25) (xy -0.5 0.25)
			)
			(stroke
				(width 0.15)
				(type solid)
			)
			(fill no)
			(layer "F.Fab")
		)
		(fp_text user "${REFERENCE}"
			(at -0.95 3.168 90)
			(layer "F.Fab")
			(effects
				(font
					(size 0.7 0.7)
					(thickness 0.15)
				)
				(justify left bottom)
			)
		)
		(fp_text user "Author: Antmicro"
			(at -0.95 4.169 90)
			(layer "F.Fab")
			(effects
				(font
					(size 0.7 0.7)
					(thickness 0.15)
				)
				(justify left bottom)
			)
		)
		(fp_text user "License: Apache-2.0"
			(at -0.949999 5.169 90)
			(layer "F.Fab")
			(effects
				(font
					(size 0.7 0.7)
					(thickness 0.15)
				)
				(justify left bottom)
			)
		)
		(pad "1" smd roundrect
			(at -0.48 0 90)
			(size 0.59 0.64)
			(layers "F.Cu" "F.Mask" "F.Paste")
			(roundrect_rratio 0.25)
			(net 870 "/SoM_IO2/TC_JTAG_TRST_N")
			(pintype "passive")
		)
		(pad "2" smd roundrect
			(at 0.48 0 90)
			(size 0.59 0.64)
			(layers "F.Cu" "F.Mask" "F.Paste")
			(roundrect_rratio 0.25)
			(net 269 "/SoM_IO2/TC_VCC")
			(pintype "passive")
		)
	)
	(footprint "antmicro-footprints:TP_SMD_0.75mm"
		(layer "F.Cu")
		(at 72 128.45)
		(property "Reference" "TP111"
			(at -0.2 -4.65 270)
			(layer "F.SilkS")
			(effects
				(font
					(size 0.7 0.7)
					(thickness 0.15)
				)
				(justify right top)
			)
		)
		(property "Value" "TP_0.75mm_SMD"
			(at 0 1.2 180)
			(layer "F.Fab")
			(effects
				(font
					(size 0.7 0.7)
					(thickness 0.15)
				)
				(justify right top)
			)
		)
		(property "Description" "SMT test point"
			(at 0 0 180)
			(layer "F.Fab")
			(hide yes)
			(effects
				(font
					(size 1.27 1.27)
					(thickness 0.15)
				)
			)
		)
		(property "MPN" ""
			(at 0 0 0)
			(unlocked yes)
			(layer "F.Fab")
			(hide yes)
			(effects
				(font
					(size 1 1)
					(thickness 0.15)
				)
			)
		)
		(property "Manufacturer" ""
			(at 0 0 0)
			(unlocked yes)
			(layer "F.Fab")
			(hide yes)
			(effects
				(font
					(size 1 1)
					(thickness 0.15)
				)
			)
		)
		(property "Author" "Antmicro"
			(at 0 0 0)
			(unlocked yes)
			(layer "F.Fab")
			(hide yes)
			(effects
				(font
					(size 1 1)
					(thickness 0.15)
				)
			)
		)
		(property "License" "Apache-2.0"
			(at 0 0 0)
			(unlocked yes)
			(layer "F.Fab")
			(hide yes)
			(effects
				(font
					(size 1 1)
					(thickness 0.15)
				)
			)
		)
		(sheetname "/Expansion connector/")
		(sheetfile "expansion_connector.kicad_sch")
		(attr exclude_from_pos_files exclude_from_bom)
		(fp_circle
			(center 0 0)
			(end 0.475 0)
			(stroke
				(width 0.05)
				(type default)
			)
			(fill no)
			(layer "F.CrtYd")
		)
		(fp_text user "License: Apache-2.0"
			(at -0.4 5.101 180)
			(layer "F.Fab")
			(effects
				(font
					(size 0.7 0.7)
					(thickness 0.15)
				)
				(justify right top)
			)
		)
		(fp_text user "Author: Antmicro"
			(at -0.4 3.901 180)
			(layer "F.Fab")
			(effects
				(font
					(size 0.7 0.7)
					(thickness 0.15)
				)
				(justify right top)
			)
		)
		(fp_text user "${REFERENCE}"
			(at -0.4 2.7 180)
			(layer "F.Fab")
			(effects
				(font
					(size 0.7 0.7)
					(thickness 0.15)
				)
				(justify right top)
			)
		)
		(pad "1" smd circle
			(at 0 0)
			(size 0.75 0.75)
			(layers "F.Cu" "F.Mask")
			(net 360 "Net-(J18-PadK40)")
			(pinfunction "1")
			(pintype "passive")
		)
	)
	(footprint "antmicro-footprints:C_0402_1005Metric"
		(layer "F.Cu")
		(at 157.33 141.88 180)
		(descr "Capacitor SMD 0402")
		(tags "capacitor SMD 0402")
		(property "Reference" "C206"
			(at -1.37 3.78 0)
			(layer "F.SilkS")
			(effects
				(font
					(size 0.7 0.7)
					(thickness 0.15)
				)
				(justify right top)
			)
		)
		(property "Value" "C_100n_0402"
			(at -1.022927 2.155213 0)
			(layer "F.Fab")
			(effects
				(font
					(size 0.7 0.7)
					(thickness 0.15)
				)
				(justify right top)
			)
		)
		(property "Datasheet" "https://www.murata.com/products/productdetail?partno=GRM155R61H104KE14%23"
			(at 0 0 0)
			(layer "F.Fab")
			(hide yes)
			(effects
				(font
					(size 1.27 1.27)
					(thickness 0.15)
				)
			)
		)
		(property "Description" "SMD Multilayer Ceramic Capacitor, 0.1 µF, 50 V, 0402 [1005 Metric], ± 10%, X5R, GRM Series"
			(at 0 0 0)
			(layer "F.Fab")
			(hide yes)
			(effects
				(font
					(size 1.27 1.27)
					(thickness 0.15)
				)
			)
		)
		(property "Manufacturer" "Murata"
			(at 0 0 180)
			(unlocked yes)
			(layer "F.Fab")
			(hide yes)
			(effects
				(font
					(size 1 1)
					(thickness 0.15)
				)
			)
		)
		(property "MPN" "GRM155R61H104KE14D"
			(at 0 0 180)
			(unlocked yes)
			(layer "F.Fab")
			(hide yes)
			(effects
				(font
					(size 1 1)
					(thickness 0.15)
				)
			)
		)
		(property "Val" "100n"
			(at 0 0 180)
			(unlocked yes)
			(layer "F.Fab")
			(hide yes)
			(effects
				(font
					(size 1 1)
					(thickness 0.15)
				)
			)
		)
		(property "License" "Apache-2.0"
			(at 0 0 180)
			(unlocked yes)
			(layer "F.Fab")
			(hide yes)
			(effects
				(font
					(size 1 1)
					(thickness 0.15)
				)
			)
		)
		(property "Author" "Antmicro"
			(at 0 0 180)
			(unlocked yes)
			(layer "F.Fab")
			(hide yes)
			(effects
				(font
					(size 1 1)
					(thickness 0.15)
				)
			)
		)
		(property "Voltage" "50V"
			(at 0 0 180)
			(unlocked yes)
			(layer "F.Fab")
			(hide yes)
			(effects
				(font
					(size 1 1)
					(thickness 0.15)
				)
			)
		)
		(property "Dielectric" "X5R"
			(at 0 0 180)
			(unlocked yes)
			(layer "F.Fab")
			(hide yes)
			(effects
				(font
					(size 1 1)
					(thickness 0.15)
				)
			)
		)
		(sheetname "/Peripherals/")
		(sheetfile "peripherals.kicad_sch")
		(attr smd)
		(fp_rect
			(start -0.925 -0.47)
			(end 0.925 0.47)
			(stroke
				(width 0.05)
				(type default)
			)
			(fill no)
			(layer "F.CrtYd")
		)
		(fp_line
			(start 0.504 0.248)
			(end -0.494 0.248)
			(stroke
				(width 0.15)
				(type solid)
			)
			(layer "F.Fab")
		)
		(fp_line
			(start 0.504 -0.25)
			(end 0.504 0.248)
			(stroke
				(width 0.15)
				(type solid)
			)
			(layer "F.Fab")
		)
		(fp_line
			(start -0.494 0.248)
			(end -0.494 -0.25)
			(stroke
				(width 0.15)
				(type solid)
			)
			(layer "F.Fab")
		)
		(fp_line
			(start -0.494 -0.25)
			(end 0.504 -0.25)
			(stroke
				(width 0.15)
				(type solid)
			)
			(layer "F.Fab")
		)
		(fp_text user "${REFERENCE}"
			(at -0.939 4.599 0)
			(layer "F.Fab")
			(effects
				(font
					(size 0.7 0.7)
					(thickness 0.15)
				)
				(justify right top)
			)
		)
		(fp_text user "Author: Antmicro"
			(at -0.939 3.399 0)
			(layer "F.Fab")
			(effects
				(font
					(size 0.7 0.7)
					(thickness 0.15)
				)
				(justify right top)
			)
		)
		(fp_text user "License: Apache-2.0"
			(at -0.939 5.799 0)
			(layer "F.Fab")
			(effects
				(font
					(size 0.7 0.7)
					(thickness 0.15)
				)
				(justify right top)
			)
		)
		(pad "1" smd roundrect
			(at -0.48 0 180)
			(size 0.59 0.64)
			(layers "F.Cu" "F.Mask" "F.Paste")
			(roundrect_rratio 0.25)
			(net 1 "GND")
			(pintype "passive")
		)
		(pad "2" smd roundrect
			(at 0.48 0 180)
			(size 0.59 0.64)
			(layers "F.Cu" "F.Mask" "F.Paste")
			(roundrect_rratio 0.25)
			(net 5 "+5V")
			(pintype "passive")
		)
	)
)
